FILE_TYPE = CONNECTIVITY;
{Allegro Design Entry HDL 17.4-2019 S026 (4007227) 1/17/2022}
"PAGE_NUMBER" = 459;
0"NC";
1"P5E_CPU1_P3_RX_DP<7:0>";
2"P5E_CPU1_P3_RX_DP<15:8>";
3"P5E_CPU1_P3_RX_DN<7:0>";
4"P5E_CPU1_P3_RX_DN<15:8>";
5"P5E_CPU1_P3_RX_DN<14>";
6"P5E_CPU1_P3_RX_DN<15>";
7"P5E_CPU1_P3_RX_DP<14>";
8"P5E_CPU1_P3_RX_DN<11>";
9"P5E_CPU1_P3_RX_DP<10>";
10"P5E_CPU1_P3_RX_DN<7>";
11"P5E_CPU1_P3_RX_DN<8>";
12"P5E_CPU1_P3_RX_DN<10>";
13"P5E_CPU1_P3_RX_DN<12>";
14"P5E_CPU1_P3_RX_DN<13>";
15"P5E_CPU1_P3_RX_DN<9>";
16"P5E_CPU1_P3_RX_DN<5>";
17"P5E_CPU1_P3_RX_DN<4>";
18"P5E_CPU1_P3_RX_DN<3>";
19"P5E_CPU1_P3_RX_DN<2>";
20"P5E_CPU1_P3_RX_DN<1>";
21"P5E_CPU1_P3_RX_DN<0>";
22"P5E_CPU1_P3_RX_DN<6>";
23"P5E_CPU1_P3_RX_DP<0>";
24"P5E_CPU1_P3_RX_DP<9>";
25"P5E_CPU1_P3_RX_DP<8>";
26"P5E_CPU1_P3_RX_DP<13>";
27"P5E_CPU1_P3_RX_DP<15>";
28"P5E_CPU1_P3_RX_DP<6>";
29"P5E_CPU1_P3_RX_DP<7>";
30"P5E_CPU1_P3_RX_DP<4>";
31"P5E_CPU1_P3_RX_DP<3>";
32"P5E_CPU1_P3_RX_DP<2>";
33"P5E_CPU1_P3_RX_DP<1>";
34"P5E_CPU1_P3_RX_DP<12>";
35"P5E_CPU1_P3_RX_DP<11>";
36"P5E_CPU1_P3_RX_DP<5>";
%"PT5161LRS"
"6","(-7625,4400)","0","pure_quanta","I1";
;
LOCATION"U6017"
$SEC"6"
CDS_SEC"6"
VALUE"PT5161LRS"
MATERIAL"IC"
PART_TYPE"SMLF"
CDS_LIB"pure_quanta"
CDS_LMAN_SYM_OUTLINE"-350,1450,300,-1400"
NEEDS_NO_SIZE"TRUE"
PART_NUMBER"AJ051610U03";
"A_PETN7"
$PN"CC29"11;
"A_PETP7"
$PN"CA26"25;
"A_PETN6"
$PN"BT29"15;
"A_PETP6"
$PN"BP26"24;
"A_PETN5"
$PN"BJ29"12;
"A_PETP5"
$PN"BG26"9;
"A_PETN4"
$PN"BB29"8;
"A_PETP4"
$PN"AY26"35;
"A_PETN3"
$PN"AR29"13;
"A_PETP3"
$PN"AN26"34;
"A_PETN2"
$PN"AH29"14;
"A_PETP2"
$PN"AF26"26;
"A_PETN1"
$PN"AA29"5;
"A_PETP1"
$PN"W26"7;
"A_PETN0"
$PN"P29"6;
"A_PETP0"
$PN"M26"27;
%"TAP"
"1","(-6400,4150)","0","standard","I10";
;
CDS_LIB"standard"
BODY_TYPE"PLUMBING"
HDL_TAP"TRUE";
"B \NAC \NWC"4;
"S \NAC"
BN"11"8;
%"TAP"
"1","(-6400,4500)","0","standard","I11";
;
CDS_LIB"standard"
BODY_TYPE"PLUMBING"
HDL_TAP"TRUE";
"B \NAC \NWC"4;
"S \NAC"
BN"12"13;
%"TAP"
"1","(-6600,4950)","0","standard","I12";
;
CDS_LIB"standard"
BODY_TYPE"PLUMBING"
HDL_TAP"TRUE";
"B \NAC \NWC"2;
"S \NAC"
BN"13"26;
%"TAP"
"1","(-6600,5300)","0","standard","I13";
;
CDS_LIB"standard"
BODY_TYPE"PLUMBING"
HDL_TAP"TRUE";
"B \NAC \NWC"2;
"S \NAC"
BN"14"7;
%"TAP"
"1","(-6600,5650)","0","standard","I14";
;
CDS_LIB"standard"
BODY_TYPE"PLUMBING"
HDL_TAP"TRUE";
"B \NAC \NWC"2;
"S \NAC"
BN"15"27;
%"TAP"
"1","(-6400,4850)","0","standard","I15";
;
CDS_LIB"standard"
BODY_TYPE"PLUMBING"
HDL_TAP"TRUE";
"B \NAC \NWC"4;
"S \NAC"
BN"13"14;
%"TAP"
"1","(-6400,5200)","0","standard","I16";
;
CDS_LIB"standard"
BODY_TYPE"PLUMBING"
HDL_TAP"TRUE";
"B \NAC \NWC"4;
"S \NAC"
BN"14"5;
%"TAP"
"1","(-6400,5550)","0","standard","I17";
;
CDS_LIB"standard"
BODY_TYPE"PLUMBING"
HDL_TAP"TRUE";
"B \NAC \NWC"4;
"S \NAC"
BN"15"6;
%"TAP"
"1","(-6600,3200)","0","standard","I2";
;
CDS_LIB"standard"
BODY_TYPE"PLUMBING"
HDL_TAP"TRUE";
"B \NAC \NWC"2;
"S \NAC"
BN"8"25;
%"TAP"
"1","(-2075,3275)","0","standard","I20";
;
CDS_LIB"standard"
BODY_TYPE"PLUMBING"
HDL_TAP"TRUE";
"B \NAC \NWC"1;
"S \NAC"
BN"0"23;
%"TAP"
"1","(-1875,3175)","0","standard","I21";
;
CDS_LIB"standard"
BODY_TYPE"PLUMBING"
HDL_TAP"TRUE";
"B \NAC \NWC"3;
"S \NAC"
BN"0"21;
%"TAP"
"1","(-1875,3525)","0","standard","I22";
;
CDS_LIB"standard"
BODY_TYPE"PLUMBING"
HDL_TAP"TRUE";
"B \NAC \NWC"3;
"S \NAC"
BN"1"20;
%"TAP"
"1","(-1875,3875)","0","standard","I23";
;
CDS_LIB"standard"
BODY_TYPE"PLUMBING"
HDL_TAP"TRUE";
"B \NAC \NWC"3;
"S \NAC"
BN"2"19;
%"TAP"
"1","(-2075,3975)","0","standard","I24";
;
CDS_LIB"standard"
BODY_TYPE"PLUMBING"
HDL_TAP"TRUE";
"B \NAC \NWC"1;
"S \NAC"
BN"2"32;
%"TAP"
"1","(-2075,4325)","0","standard","I25";
;
CDS_LIB"standard"
BODY_TYPE"PLUMBING"
HDL_TAP"TRUE";
"B \NAC \NWC"1;
"S \NAC"
BN"3"31;
%"TAP"
"1","(-1875,4225)","0","standard","I26";
;
CDS_LIB"standard"
BODY_TYPE"PLUMBING"
HDL_TAP"TRUE";
"B \NAC \NWC"3;
"S \NAC"
BN"3"18;
%"TAP"
"1","(-1875,4575)","0","standard","I27";
;
CDS_LIB"standard"
BODY_TYPE"PLUMBING"
HDL_TAP"TRUE";
"B \NAC \NWC"3;
"S \NAC"
BN"4"17;
%"TAP"
"1","(-2075,4675)","0","standard","I28";
;
CDS_LIB"standard"
BODY_TYPE"PLUMBING"
HDL_TAP"TRUE";
"B \NAC \NWC"1;
"S \NAC"
BN"4"30;
%"TAP"
"1","(-2075,5025)","0","standard","I29";
;
CDS_LIB"standard"
BODY_TYPE"PLUMBING"
HDL_TAP"TRUE";
"B \NAC \NWC"1;
"S \NAC"
BN"5"36;
%"TAP"
"1","(-6600,3550)","0","standard","I3";
;
CDS_LIB"standard"
BODY_TYPE"PLUMBING"
HDL_TAP"TRUE";
"B \NAC \NWC"2;
"S \NAC"
BN"9"24;
%"TAP"
"1","(-1875,4925)","0","standard","I30";
;
CDS_LIB"standard"
BODY_TYPE"PLUMBING"
HDL_TAP"TRUE";
"B \NAC \NWC"3;
"S \NAC"
BN"5"16;
%"TAP"
"1","(-2075,5375)","0","standard","I31";
;
CDS_LIB"standard"
BODY_TYPE"PLUMBING"
HDL_TAP"TRUE";
"B \NAC \NWC"1;
"S \NAC"
BN"6"28;
%"TAP"
"1","(-1875,5275)","0","standard","I32";
;
CDS_LIB"standard"
BODY_TYPE"PLUMBING"
HDL_TAP"TRUE";
"B \NAC \NWC"3;
"S \NAC"
BN"6"22;
%"TAP"
"1","(-1875,5625)","0","standard","I33";
;
CDS_LIB"standard"
BODY_TYPE"PLUMBING"
HDL_TAP"TRUE";
"B \NAC \NWC"3;
"S \NAC"
BN"7"10;
%"TAP"
"1","(-2075,5725)","0","standard","I34";
;
CDS_LIB"standard"
BODY_TYPE"PLUMBING"
HDL_TAP"TRUE";
"B \NAC \NWC"1;
"S \NAC"
BN"7"29;
%"TAP"
"1","(-2075,3625)","0","standard","I37";
;
CDS_LIB"standard"
BODY_TYPE"PLUMBING"
HDL_TAP"TRUE";
"B \NAC \NWC"1;
"S \NAC"
BN"1"33;
%"PT5161LRS"
"7","(-3100,4475)","0","pure_quanta","I38";
;
LOCATION"U6017"
$SEC"7"
CDS_SEC"7"
VALUE"PT5161LRS"
PART_TYPE"SMLF"
MATERIAL"IC"
NEEDS_NO_SIZE"TRUE"
CDS_LMAN_SYM_OUTLINE"-350,1450,300,-1400"
CDS_LIB"pure_quanta"
PART_NUMBER"AJ051610U03";
"A_PETN15"
$PN"EW29"21;
"A_PETP15"
$PN"EU26"23;
"A_PETN14"
$PN"EM29"20;
"A_PETP14"
$PN"EK26"33;
"A_PETN13"
$PN"EE29"19;
"A_PETP13"
$PN"EC26"32;
"A_PETN12"
$PN"DV29"18;
"A_PETP12"
$PN"DT26"31;
"A_PETN11"
$PN"DL29"17;
"A_PETP11"
$PN"DJ26"30;
"A_PETN10"
$PN"DD29"16;
"A_PETP10"
$PN"DB26"36;
"A_PETN9"
$PN"CU29"22;
"A_PETP9"
$PN"CR26"28;
"A_PETN8"
$PN"CK29"10;
"A_PETP8"
$PN"CH26"29;
%"TAP"
"1","(-6400,3100)","0","standard","I4";
;
CDS_LIB"standard"
BODY_TYPE"PLUMBING"
HDL_TAP"TRUE";
"B \NAC \NWC"4;
"S \NAC"
BN"8"11;
%"TAP"
"1","(-6400,3450)","0","standard","I5";
;
CDS_LIB"standard"
BODY_TYPE"PLUMBING"
HDL_TAP"TRUE";
"B \NAC \NWC"4;
"S \NAC"
BN"9"15;
%"TAP"
"1","(-6600,3900)","0","standard","I6";
;
CDS_LIB"standard"
BODY_TYPE"PLUMBING"
HDL_TAP"TRUE";
"B \NAC \NWC"2;
"S \NAC"
BN"10"9;
%"TAP"
"1","(-6600,4250)","0","standard","I7";
;
CDS_LIB"standard"
BODY_TYPE"PLUMBING"
HDL_TAP"TRUE";
"B \NAC \NWC"2;
"S \NAC"
BN"11"35;
%"TAP"
"1","(-6600,4600)","0","standard","I8";
;
CDS_LIB"standard"
BODY_TYPE"PLUMBING"
HDL_TAP"TRUE";
"B \NAC \NWC"2;
"S \NAC"
BN"12"34;
%"TAP"
"1","(-6400,3800)","0","standard","I9";
;
CDS_LIB"standard"
BODY_TYPE"PLUMBING"
HDL_TAP"TRUE";
"B \NAC \NWC"4;
"S \NAC"
BN"10"12;
END.
